(kicad_pcb
	(version 20241229)
	(generator "pcbnew")
	(generator_version "9.0")
	(general
		(thickness 1.6)
		(legacy_teardrops no)
	)
	(paper "A4")
	(title_block
		(title "OCuLink to PCIe adapter")
		(date "2025-06-18")
		(rev "1.0.0")
		(company "Antmicro Ltd")
		(comment 1 "www.antmicro.com")
		(comment 9 "footprints 73-77 of 159")
	)
	(layers
		(0 "F.Cu" signal)
		(4 "In1.Cu" signal)
		(6 "In2.Cu" signal)
		(2 "B.Cu" signal)
		(9 "F.Adhes" user "F.Adhesive")
		(11 "B.Adhes" user "B.Adhesive")
		(13 "F.Paste" user)
		(15 "B.Paste" user)
		(5 "F.SilkS" user "F.Silkscreen")
		(7 "B.SilkS" user "B.Silkscreen")
		(1 "F.Mask" user)
		(3 "B.Mask" user)
		(17 "Dwgs.User" user "User.Drawings")
		(19 "Cmts.User" user "User.Comments")
		(21 "Eco1.User" user "User.Eco1")
		(23 "Eco2.User" user "User.Eco2")
		(25 "Edge.Cuts" user)
		(27 "Margin" user)
		(31 "F.CrtYd" user "F.Courtyard")
		(29 "B.CrtYd" user "B.Courtyard")
		(35 "F.Fab" user)
		(33 "B.Fab" user)
	)
	(footprint "antmicro-footprints:C_0805_2012Metric"
		(layer "F.Cu")
		(at 128.900001 131.05 -90)
		(descr "Capacitor SMD 0805")
		(tags "capacitor SMD 0805")
		(property "Reference" "C15"
			(at -5.05 0.400001 90)
			(layer "F.SilkS")
			(effects
				(font
					(size 0.7 0.7)
					(thickness 0.15)
				)
				(justify right top)
			)
		)
		(property "Value" "C_22u_25V_0805"
			(at -2.055717 1.963153 90)
			(layer "F.Fab")
			(effects
				(font
					(size 0.7 0.7)
					(thickness 0.15)
				)
				(justify right top)
			)
		)
		(property "Datasheet" "https://product.samsungsem.com/mlcc/CL21A226MAYNNN.do"
			(at 0 0 90)
			(layer "F.Fab")
			(hide yes)
			(effects
				(font
					(size 1.27 1.27)
					(thickness 0.15)
				)
			)
		)
		(property "Description" "SMT Multilayer Ceramic Capacitor, 22uF, +/-20%, 25V, X5R, 0805 [2012 Metric]"
			(at 0 0 90)
			(layer "F.Fab")
			(hide yes)
			(effects
				(font
					(size 1.27 1.27)
					(thickness 0.15)
				)
			)
		)
		(property "MPN" "CL21A226MAYNNNE"
			(at 0 0 270)
			(unlocked yes)
			(layer "F.Fab")
			(hide yes)
			(effects
				(font
					(size 1 1)
					(thickness 0.15)
				)
			)
		)
		(property "Manufacturer" "Samsung Electro-Mechanics"
			(at 0 0 270)
			(unlocked yes)
			(layer "F.Fab")
			(hide yes)
			(effects
				(font
					(size 1 1)
					(thickness 0.15)
				)
			)
		)
		(property "License" "Apache-2.0"
			(at 0 0 270)
			(unlocked yes)
			(layer "F.Fab")
			(hide yes)
			(effects
				(font
					(size 1 1)
					(thickness 0.15)
				)
			)
		)
		(property "Author" "Antmicro"
			(at 0 0 270)
			(unlocked yes)
			(layer "F.Fab")
			(hide yes)
			(effects
				(font
					(size 1 1)
					(thickness 0.15)
				)
			)
		)
		(property "Val" "22u"
			(at 0 0 270)
			(unlocked yes)
			(layer "F.Fab")
			(hide yes)
			(effects
				(font
					(size 1 1)
					(thickness 0.15)
				)
			)
		)
		(property "Voltage" "25V"
			(at 0 0 270)
			(unlocked yes)
			(layer "F.Fab")
			(hide yes)
			(effects
				(font
					(size 1 1)
					(thickness 0.15)
				)
			)
		)
		(property "Dielectric" "X5R"
			(at 0 0 270)
			(unlocked yes)
			(layer "F.Fab")
			(hide yes)
			(effects
				(font
					(size 1 1)
					(thickness 0.15)
				)
			)
		)
		(property "Public" "False"
			(at 0 0 270)
			(unlocked yes)
			(layer "F.Fab")
			(hide yes)
			(effects
				(font
					(size 1 1)
					(thickness 0.15)
				)
			)
		)
		(sheetname "/Power/")
		(sheetfile "power.kicad_sch")
		(attr smd)
		(fp_line
			(start -0.3 0.7)
			(end 0.3 0.7)
			(stroke
				(width 0.15)
				(type solid)
			)
			(layer "F.SilkS")
		)
		(fp_line
			(start -0.3 -0.7)
			(end 0.3 -0.7)
			(stroke
				(width 0.15)
				(type solid)
			)
			(layer "F.SilkS")
		)
		(fp_rect
			(start 1.95 -0.9)
			(end -1.95 0.9)
			(stroke
				(width 0.05)
				(type default)
			)
			(fill no)
			(layer "F.CrtYd")
		)
		(fp_rect
			(start -0.95 -0.675)
			(end 0.95 0.675)
			(stroke
				(width 0.15)
				(type solid)
			)
			(fill no)
			(layer "F.Fab")
		)
		(fp_text user "Author: Antmicro"
			(at -1.9 5.947 90)
			(layer "F.Fab")
			(effects
				(font
					(size 0.7 0.7)
					(thickness 0.15)
				)
				(justify right top)
			)
		)
		(fp_text user "${REFERENCE}"
			(at -1.899999 3.947 90)
			(layer "F.Fab")
			(effects
				(font
					(size 0.7 0.7)
					(thickness 0.15)
				)
				(justify right top)
			)
		)
		(fp_text user "License: Apache-2.0"
			(at -1.9 4.947 90)
			(layer "F.Fab")
			(effects
				(font
					(size 0.7 0.7)
					(thickness 0.15)
				)
				(justify right top)
			)
		)
		(pad "1" smd roundrect
			(at -1.1 0 270)
			(size 1.2 1.3)
			(layers "F.Cu" "F.Mask" "F.Paste")
			(roundrect_rratio 0.25)
			(net 66 "GND")
			(pintype "passive")
		)
		(pad "2" smd roundrect
			(at 1.1 0 270)
			(size 1.2 1.3)
			(layers "F.Cu" "F.Mask" "F.Paste")
			(roundrect_rratio 0.25)
			(net 87 "+12V")
			(pintype "passive")
		)
	)
	(footprint "antmicro-footprints:R_0402_1005Metric"
		(layer "F.Cu")
		(at 146.737 57.376 -90)
		(descr "Resistor SMD 0402")
		(tags "resistor SMD 0402")
		(property "Reference" "R29"
			(at 1.074 0.360999 90)
			(layer "F.SilkS")
			(effects
				(font
					(size 0.7 0.7)
					(thickness 0.15)
				)
				(justify right top)
			)
		)
		(property "Value" "R_1k_0402"
			(at -1.011843 1.772046 90)
			(layer "F.Fab")
			(effects
				(font
					(size 0.7 0.7)
					(thickness 0.15)
				)
				(justify right top)
			)
		)
		(property "Datasheet" "https://www.bourns.com/docs/product-datasheets/cr.pdf"
			(at 0 0 90)
			(layer "F.Fab")
			(hide yes)
			(effects
				(font
					(size 1.27 1.27)
					(thickness 0.15)
				)
			)
		)
		(property "Description" "SMD Chip Resistor, 1 kohm, ± 1%, 63 mW, 0402 [1005 Metric], Thick Film, General Purpose"
			(at 0 0 90)
			(layer "F.Fab")
			(hide yes)
			(effects
				(font
					(size 1.27 1.27)
					(thickness 0.15)
				)
			)
		)
		(property "MPN" "CR0402-FX-1001GLF"
			(at 0 0 270)
			(unlocked yes)
			(layer "F.Fab")
			(hide yes)
			(effects
				(font
					(size 1 1)
					(thickness 0.15)
				)
			)
		)
		(property "Manufacturer" "Bourns"
			(at 0 0 270)
			(unlocked yes)
			(layer "F.Fab")
			(hide yes)
			(effects
				(font
					(size 1 1)
					(thickness 0.15)
				)
			)
		)
		(property "License" "Apache-2.0"
			(at 0 0 270)
			(unlocked yes)
			(layer "F.Fab")
			(hide yes)
			(effects
				(font
					(size 1 1)
					(thickness 0.15)
				)
			)
		)
		(property "Author" "Antmicro"
			(at 0 0 270)
			(unlocked yes)
			(layer "F.Fab")
			(hide yes)
			(effects
				(font
					(size 1 1)
					(thickness 0.15)
				)
			)
		)
		(property "Val" "1k"
			(at 0 0 270)
			(unlocked yes)
			(layer "F.Fab")
			(hide yes)
			(effects
				(font
					(size 1 1)
					(thickness 0.15)
				)
			)
		)
		(property "Tolerance" "1%"
			(at 0 0 270)
			(unlocked yes)
			(layer "F.Fab")
			(hide yes)
			(effects
				(font
					(size 1 1)
					(thickness 0.15)
				)
			)
		)
		(sheetname "/USB-PD/")
		(sheetfile "usb-pd.kicad_sch")
		(attr smd)
		(fp_rect
			(start -0.925 -0.47)
			(end 0.925 0.47)
			(stroke
				(width 0.05)
				(type default)
			)
			(fill no)
			(layer "F.CrtYd")
		)
		(fp_rect
			(start -0.5 -0.25)
			(end 0.5 0.25)
			(stroke
				(width 0.15)
				(type solid)
			)
			(fill no)
			(layer "F.Fab")
		)
		(fp_text user "${REFERENCE}"
			(at 0 0 90)
			(layer "F.Fab")
			(effects
				(font
					(size 0.7 0.7)
					(thickness 0.15)
				)
				(justify right top)
			)
		)
		(fp_text user "Author: Antmicro"
			(at -0.95 4.169 90)
			(layer "F.Fab")
			(effects
				(font
					(size 0.7 0.7)
					(thickness 0.15)
				)
				(justify right top)
			)
		)
		(fp_text user "License: Apache-2.0"
			(at -0.949999 5.169 90)
			(layer "F.Fab")
			(effects
				(font
					(size 0.7 0.7)
					(thickness 0.15)
				)
				(justify right top)
			)
		)
		(pad "1" smd roundrect
			(at -0.48 0 270)
			(size 0.59 0.64)
			(layers "F.Cu" "F.Mask" "F.Paste")
			(roundrect_rratio 0.25)
			(net 133 "/USB-PD/VBUS_MIN")
			(pintype "passive")
		)
		(pad "2" smd roundrect
			(at 0.48 0 270)
			(size 0.59 0.64)
			(layers "F.Cu" "F.Mask" "F.Paste")
			(roundrect_rratio 0.25)
			(net 117 "/USB-PD/VDDD_3V3")
			(pintype "passive")
		)
	)
	(footprint "antmicro-footprints:C_Pol_Vishay-T59-EE"
		(layer "F.Cu")
		(at 138.5 77 180)
		(property "Reference" "C43"
			(at -5.1 -0.4 180)
			(layer "F.SilkS")
			(effects
				(font
					(size 0.7 0.7)
					(thickness 0.15)
				)
				(justify left bottom)
			)
		)
		(property "Value" "C_Pol_150u_30V_Vishay-T59-EE"
			(at -5.08 5.08 180)
			(unlocked yes)
			(layer "F.Fab")
			(effects
				(font
					(size 0.7 0.7)
					(thickness 0.15)
				)
				(justify left bottom)
			)
		)
		(property "Datasheet" "https://www.vishay.com/docs/40191/t59.pdf"
			(at 0 0 0)
			(layer "F.Fab")
			(hide yes)
			(effects
				(font
					(size 1.27 1.27)
					(thickness 0.15)
				)
			)
		)
		(property "Description" "Tantalum Capacitors - Polymer 150uF 30volts 20% 75mohms maxESR"
			(at 0 0 0)
			(layer "F.Fab")
			(hide yes)
			(effects
				(font
					(size 1.27 1.27)
					(thickness 0.15)
				)
			)
		)
		(property "MPN" "T59EE157M030C0075"
			(at 0 0 180)
			(unlocked yes)
			(layer "F.Fab")
			(hide yes)
			(effects
				(font
					(size 1 1)
					(thickness 0.15)
				)
			)
		)
		(property "Manufacturer" "Vishay"
			(at 0 0 180)
			(unlocked yes)
			(layer "F.Fab")
			(hide yes)
			(effects
				(font
					(size 1 1)
					(thickness 0.15)
				)
			)
		)
		(property "Voltage" "30V"
			(at 0 0 180)
			(unlocked yes)
			(layer "F.Fab")
			(hide yes)
			(effects
				(font
					(size 1 1)
					(thickness 0.15)
				)
			)
		)
		(property "Val" "150u"
			(at 0 0 180)
			(unlocked yes)
			(layer "F.Fab")
			(hide yes)
			(effects
				(font
					(size 1 1)
					(thickness 0.15)
				)
			)
		)
		(property "Author" "Antmicro"
			(at 0 0 180)
			(unlocked yes)
			(layer "F.Fab")
			(hide yes)
			(effects
				(font
					(size 1 1)
					(thickness 0.15)
				)
			)
		)
		(property "License" "Apache-2.0"
			(at 0 0 180)
			(unlocked yes)
			(layer "F.Fab")
			(hide yes)
			(effects
				(font
					(size 1 1)
					(thickness 0.15)
				)
			)
		)
		(property "Dielectric" "template_dielectric"
			(at 0 0 180)
			(unlocked yes)
			(layer "F.Fab")
			(hide yes)
			(effects
				(font
					(size 1 1)
					(thickness 0.15)
				)
			)
		)
		(sheetname "/USB-PD/")
		(sheetfile "usb-pd.kicad_sch")
		(attr smd)
		(fp_line
			(start -2 2.25)
			(end 2 2.25)
			(stroke
				(width 0.15)
				(type solid)
			)
			(layer "F.SilkS")
		)
		(fp_line
			(start -2 -2.25)
			(end 2 -2.25)
			(stroke
				(width 0.15)
				(type solid)
			)
			(layer "F.SilkS")
		)
		(fp_line
			(start -3.5 -2.8)
			(end -3.5 -3.2)
			(stroke
				(width 0.15)
				(type solid)
			)
			(layer "F.SilkS")
		)
		(fp_line
			(start -3.7 -3)
			(end -3.3 -3)
			(stroke
				(width 0.15)
				(type solid)
			)
			(layer "F.SilkS")
		)
		(fp_rect
			(start -4.9 -2.9)
			(end 4.9 2.9)
			(stroke
				(width 0.05)
				(type solid)
			)
			(fill no)
			(layer "F.CrtYd")
		)
		(fp_rect
			(start -3.75 -2.25)
			(end 3.75 2.25)
			(stroke
				(width 0.15)
				(type solid)
			)
			(fill no)
			(layer "F.Fab")
		)
		(fp_text user "Author: Antmicro"
			(at -5.079999 7.08 0)
			(layer "F.Fab")
			(effects
				(font
					(size 0.7 0.7)
					(thickness 0.15)
				)
				(justify right top)
			)
		)
		(fp_text user "${REFERENCE}"
			(at 0 -0.175 180)
			(layer "F.Fab")
			(effects
				(font
					(size 0.7 0.7)
					(thickness 0.15)
				)
				(justify left bottom)
			)
		)
		(fp_text user "License: Apache-2.0"
			(at -5.08 9.48 0)
			(layer "F.Fab")
			(effects
				(font
					(size 0.7 0.7)
					(thickness 0.15)
				)
				(justify right top)
			)
		)
		(pad "1" smd trapezoid
			(at -3.4 0 180)
			(size 2.5 5.3)
			(layers "F.Cu" "F.Mask" "F.Paste")
			(net 115 "/USB-PD/VCC")
			(pintype "passive")
		)
		(pad "2" smd trapezoid
			(at 3.4 0 180)
			(size 2.5 5.3)
			(layers "F.Cu" "F.Mask" "F.Paste")
			(net 66 "GND")
			(pintype "passive")
		)
	)
	(footprint "antmicro-footprints:R_0402_1005Metric"
		(layer "F.Cu")
		(at 154.312 53.000999)
		(descr "Resistor SMD 0402")
		(tags "resistor SMD 0402")
		(property "Reference" "R20"
			(at 1.088 0.399001 180)
			(layer "F.SilkS")
			(effects
				(font
					(size 0.7 0.7)
					(thickness 0.15)
				)
				(justify left bottom)
			)
		)
		(property "Value" "R_49k9_0402"
			(at -1.011843 1.772046 0)
			(layer "F.Fab")
			(effects
				(font
					(size 0.7 0.7)
					(thickness 0.15)
				)
				(justify left bottom)
			)
		)
		(property "Datasheet" "https://www.bourns.com/docs/product-datasheets/cr.pdf"
			(at 0 0 0)
			(layer "F.Fab")
			(hide yes)
			(effects
				(font
					(size 1.27 1.27)
					(thickness 0.15)
				)
			)
		)
		(property "Description" "SMD Chip Resistor, 49.9 kohm, ± 1%, 63 mW, 0402 [1005 Metric], Thick Film, General Purpose"
			(at 0 0 0)
			(layer "F.Fab")
			(hide yes)
			(effects
				(font
					(size 1.27 1.27)
					(thickness 0.15)
				)
			)
		)
		(property "MPN" "CR0402-FX-4992GLF"
			(at 0 0 0)
			(unlocked yes)
			(layer "F.Fab")
			(hide yes)
			(effects
				(font
					(size 1 1)
					(thickness 0.15)
				)
			)
		)
		(property "Manufacturer" "Bourns"
			(at 0 0 0)
			(unlocked yes)
			(layer "F.Fab")
			(hide yes)
			(effects
				(font
					(size 1 1)
					(thickness 0.15)
				)
			)
		)
		(property "License" "Apache-2.0"
			(at 0 0 0)
			(unlocked yes)
			(layer "F.Fab")
			(hide yes)
			(effects
				(font
					(size 1 1)
					(thickness 0.15)
				)
			)
		)
		(property "Author" "Antmicro"
			(at 0 0 0)
			(unlocked yes)
			(layer "F.Fab")
			(hide yes)
			(effects
				(font
					(size 1 1)
					(thickness 0.15)
				)
			)
		)
		(property "Val" "49k9"
			(at 0 0 0)
			(unlocked yes)
			(layer "F.Fab")
			(hide yes)
			(effects
				(font
					(size 1 1)
					(thickness 0.15)
				)
			)
		)
		(property "Tolerance" "1%"
			(at 0 0 0)
			(unlocked yes)
			(layer "F.Fab")
			(hide yes)
			(effects
				(font
					(size 1 1)
					(thickness 0.15)
				)
			)
		)
		(sheetname "/USB-PD/")
		(sheetfile "usb-pd.kicad_sch")
		(attr smd)
		(fp_rect
			(start -0.925 -0.47)
			(end 0.925 0.47)
			(stroke
				(width 0.05)
				(type default)
			)
			(fill no)
			(layer "F.CrtYd")
		)
		(fp_rect
			(start -0.5 -0.25)
			(end 0.5 0.25)
			(stroke
				(width 0.15)
				(type solid)
			)
			(fill no)
			(layer "F.Fab")
		)
		(fp_text user "License: Apache-2.0"
			(at -0.949999 5.169 0)
			(layer "F.Fab")
			(effects
				(font
					(size 0.7 0.7)
					(thickness 0.15)
				)
				(justify left bottom)
			)
		)
		(fp_text user "Author: Antmicro"
			(at -0.95 4.169 0)
			(layer "F.Fab")
			(effects
				(font
					(size 0.7 0.7)
					(thickness 0.15)
				)
				(justify left bottom)
			)
		)
		(fp_text user "${REFERENCE}"
			(at 0 0 0)
			(layer "F.Fab")
			(effects
				(font
					(size 0.7 0.7)
					(thickness 0.15)
				)
				(justify left bottom)
			)
		)
		(pad "1" smd roundrect
			(at -0.48 0)
			(size 0.59 0.64)
			(layers "F.Cu" "F.Mask" "F.Paste")
			(roundrect_rratio 0.25)
			(net 135 "/USB-PD/FLIP")
			(pintype "passive")
		)
		(pad "2" smd roundrect
			(at 0.48 0)
			(size 0.59 0.64)
			(layers "F.Cu" "F.Mask" "F.Paste")
			(roundrect_rratio 0.25)
			(net 117 "/USB-PD/VDDD_3V3")
			(pintype "passive")
		)
	)
	(footprint "antmicro-footprints:R_0402_1005Metric"
		(layer "F.Cu")
		(at 153.736999 57.376001 90)
		(descr "Resistor SMD 0402")
		(tags "resistor SMD 0402")
		(property "Reference" "R21"
			(at -3.273999 0.439002 90)
			(layer "F.SilkS")
			(effects
				(font
					(size 0.7 0.7)
					(thickness 0.15)
				)
				(justify left bottom)
			)
		)
		(property "Value" "R_1k_0402"
			(at -1.011843 1.772046 90)
			(layer "F.Fab")
			(effects
				(font
					(size 0.7 0.7)
					(thickness 0.15)
				)
				(justify left bottom)
			)
		)
		(property "Datasheet" "https://www.bourns.com/docs/product-datasheets/cr.pdf"
			(at 0 0 90)
			(layer "F.Fab")
			(hide yes)
			(effects
				(font
					(size 1.27 1.27)
					(thickness 0.15)
				)
			)
		)
		(property "Description" "SMD Chip Resistor, 1 kohm, ± 1%, 63 mW, 0402 [1005 Metric], Thick Film, General Purpose"
			(at 0 0 90)
			(layer "F.Fab")
			(hide yes)
			(effects
				(font
					(size 1.27 1.27)
					(thickness 0.15)
				)
			)
		)
		(property "MPN" "CR0402-FX-1001GLF"
			(at 0 0 90)
			(unlocked yes)
			(layer "F.Fab")
			(hide yes)
			(effects
				(font
					(size 1 1)
					(thickness 0.15)
				)
			)
		)
		(property "Manufacturer" "Bourns"
			(at 0 0 90)
			(unlocked yes)
			(layer "F.Fab")
			(hide yes)
			(effects
				(font
					(size 1 1)
					(thickness 0.15)
				)
			)
		)
		(property "License" "Apache-2.0"
			(at 0 0 90)
			(unlocked yes)
			(layer "F.Fab")
			(hide yes)
			(effects
				(font
					(size 1 1)
					(thickness 0.15)
				)
			)
		)
		(property "Author" "Antmicro"
			(at 0 0 90)
			(unlocked yes)
			(layer "F.Fab")
			(hide yes)
			(effects
				(font
					(size 1 1)
					(thickness 0.15)
				)
			)
		)
		(property "Val" "1k"
			(at 0 0 90)
			(unlocked yes)
			(layer "F.Fab")
			(hide yes)
			(effects
				(font
					(size 1 1)
					(thickness 0.15)
				)
			)
		)
		(property "Tolerance" "1%"
			(at 0 0 90)
			(unlocked yes)
			(layer "F.Fab")
			(hide yes)
			(effects
				(font
					(size 1 1)
					(thickness 0.15)
				)
			)
		)
		(sheetname "/USB-PD/")
		(sheetfile "usb-pd.kicad_sch")
		(attr smd)
		(fp_rect
			(start -0.925 -0.47)
			(end 0.925 0.47)
			(stroke
				(width 0.05)
				(type default)
			)
			(fill no)
			(layer "F.CrtYd")
		)
		(fp_rect
			(start -0.5 -0.25)
			(end 0.5 0.25)
			(stroke
				(width 0.15)
				(type solid)
			)
			(fill no)
			(layer "F.Fab")
		)
		(fp_text user "${REFERENCE}"
			(at 0 0 90)
			(layer "F.Fab")
			(effects
				(font
					(size 0.7 0.7)
					(thickness 0.15)
				)
				(justify left bottom)
			)
		)
		(fp_text user "License: Apache-2.0"
			(at -0.949999 5.169 90)
			(layer "F.Fab")
			(effects
				(font
					(size 0.7 0.7)
					(thickness 0.15)
				)
				(justify left bottom)
			)
		)
		(fp_text user "Author: Antmicro"
			(at -0.95 4.169 90)
			(layer "F.Fab")
			(effects
				(font
					(size 0.7 0.7)
					(thickness 0.15)
				)
				(justify left bottom)
			)
		)
		(pad "1" smd roundrect
			(at -0.48 0 90)
			(size 0.59 0.64)
			(layers "F.Cu" "F.Mask" "F.Paste")
			(roundrect_rratio 0.25)
			(net 66 "GND")
			(pintype "passive")
		)
		(pad "2" smd roundrect
			(at 0.48 0 90)
			(size 0.59 0.64)
			(layers "F.Cu" "F.Mask" "F.Paste")
			(roundrect_rratio 0.25)
			(net 137 "/USB-PD/ISNK_FINE")
			(pintype "passive")
		)
	)
)
